# T6G (Grand Teton) — schematic netlist excerpt (pin names and nets, part order shuffled) for the footprints in the layout excerpt that follows; sources: Cadence DE-HDL packaged netlist, KiCad conversion of 04192023_DAF0TMB3IC0_F0TG_MB_C_brd_V02_OCP.brd

R503  Q_RES  15 1% CHIP  pkg 0402LF  page 40 : A = M_D_CPU1_ALERT_N ; B = M_D_CPU1_ALERT_R_N
C8013  Q_CAP  0.1UF 25V 10% EMPTY  pkg 0402  page 242 : A = P3V3_AUX ; B = GND
C315  Q_CAP  1UF 4V 20% X6S  pkg 0201  page 334 : A = P0V9_CPU1_RT1_2A_2D ; B = GND

(kicad_pcb
	(version 20260206)
	(generator "pcbnew")
	(generator_version "10.0")
	(general
		(thickness 1.6)
		(legacy_teardrops no)
	)
	(paper "A4")
	(title_block
		(title "04192023_DAF0TMB3IC0_F0TG_MB_C_brd_V02_OCP.brd")
		(comment 1 "Grand Teton / footprints 6911-6913 of 8354")
	)
	(layers
		(0 "F.Cu" signal "TOP")
		(4 "In1.Cu" signal "GND")
		(6 "In2.Cu" signal "IN1")
		(8 "In3.Cu" signal "GND1")
		(10 "In4.Cu" signal "IN2")
		(12 "In5.Cu" signal "GND2")
		(14 "In6.Cu" signal "IN3")
		(16 "In7.Cu" signal "GND3")
		(18 "In8.Cu" signal "VCC")
		(20 "In9.Cu" signal "VCC1")
		(22 "In10.Cu" signal "GND4")
		(24 "In11.Cu" signal "IN4")
		(26 "In12.Cu" signal "GND5")
		(28 "In13.Cu" signal "IN5")
		(30 "In14.Cu" signal "GND6")
		(32 "In15.Cu" signal "IN6")
		(34 "In16.Cu" signal "GND7")
		(2 "B.Cu" signal "BOTTOM")
		(9 "F.Adhes" user "F.Adhesive")
		(11 "B.Adhes" user "B.Adhesive")
		(13 "F.Paste" user "Package Geometry/Pastemask Top")
		(15 "B.Paste" user "Package Geometry/Pastemask Bottom")
		(5 "F.SilkS" user "Ref Des/Silkscreen Top")
		(7 "B.SilkS" user "Ref Des/Silkscreen Bottom")
		(1 "F.Mask" user "Board Geometry/Soldermask Top")
		(3 "B.Mask" user "Board Geometry/Soldermask Bottom")
		(17 "Dwgs.User" user "User.Drawings")
		(19 "Cmts.User" user "User.Comments")
		(21 "Eco1.User" user "User.Eco1")
		(23 "Eco2.User" user "User.Eco2")
		(25 "Edge.Cuts" user "Board Geometry/Outline")
		(27 "Margin" user)
		(31 "F.CrtYd" user "Package Geometry/Place Bound Top")
		(29 "B.CrtYd" user "Package Geometry/Place Bound Bottom")
		(35 "F.Fab" user "Ref Des/Assembly Top")
		(33 "B.Fab" user "Ref Des/Assembly Bottom")
	)
	(footprint ""
		(layer "B.Cu")
		(at 201.041 -137.922 90)
		(property "Reference" "C8013"
			(at 0 0 90)
			(layer "B.SilkS")
			(hide yes)
			(effects
				(font
					(size 1.27 1.27)
				)
				(justify mirror)
			)
		)
		(property "Value" ""
			(at 0 0 90)
			(layer "B.Fab")
			(effects
				(font
					(size 1.27 1.27)
				)
				(justify mirror)
			)
		)
		(duplicate_pad_numbers_are_jumpers no)
		(fp_line
			(start 0.7874 -0.4064)
			(end -0.7874 -0.4064)
			(stroke
				(width 0.1524)
				(type default)
			)
			(layer "B.SilkS")
		)
		(fp_line
			(start -0.7874 -0.4064)
			(end -0.7874 0.4064)
			(stroke
				(width 0.1524)
				(type default)
			)
			(layer "B.SilkS")
		)
		(fp_line
			(start 0.7874 0.4064)
			(end 0.7874 -0.4064)
			(stroke
				(width 0.1524)
				(type default)
			)
			(layer "B.SilkS")
		)
		(fp_line
			(start -0.7874 0.4064)
			(end 0.7874 0.4064)
			(stroke
				(width 0.1524)
				(type default)
			)
			(layer "B.SilkS")
		)
		(fp_line
			(start 0.67945 -0.305054)
			(end 0.12065 -0.305054)
			(stroke
				(width 0.1)
				(type default)
			)
			(layer "B.Fab")
		)
		(fp_line
			(start 0.12065 -0.305054)
			(end 0.12065 -0.2794)
			(stroke
				(width 0.1)
				(type default)
			)
			(layer "B.Fab")
		)
		(fp_line
			(start -0.12065 -0.3048)
			(end -0.67945 -0.3048)
			(stroke
				(width 0.1)
				(type default)
			)
			(layer "B.Fab")
		)
		(fp_line
			(start -0.67945 -0.3048)
			(end -0.67945 0.3048)
			(stroke
				(width 0.1)
				(type default)
			)
			(layer "B.Fab")
		)
		(fp_line
			(start 0.12065 -0.2794)
			(end -0.12065 -0.2794)
			(stroke
				(width 0.1)
				(type default)
			)
			(layer "B.Fab")
		)
		(fp_line
			(start -0.12065 -0.2794)
			(end -0.12065 -0.3048)
			(stroke
				(width 0.1)
				(type default)
			)
			(layer "B.Fab")
		)
		(fp_line
			(start 0.12065 0.2794)
			(end 0.12065 0.3048)
			(stroke
				(width 0.1)
				(type default)
			)
			(layer "B.Fab")
		)
		(fp_line
			(start -0.120396 0.2794)
			(end 0.12065 0.2794)
			(stroke
				(width 0.1)
				(type default)
			)
			(layer "B.Fab")
		)
		(fp_line
			(start 0.67945 0.3048)
			(end 0.67945 -0.305054)
			(stroke
				(width 0.1)
				(type default)
			)
			(layer "B.Fab")
		)
		(fp_line
			(start 0.12065 0.3048)
			(end 0.67945 0.3048)
			(stroke
				(width 0.1)
				(type default)
			)
			(layer "B.Fab")
		)
		(fp_line
			(start -0.120396 0.3048)
			(end -0.120396 0.2794)
			(stroke
				(width 0.1)
				(type default)
			)
			(layer "B.Fab")
		)
		(fp_line
			(start -0.67945 0.3048)
			(end -0.120396 0.3048)
			(stroke
				(width 0.1)
				(type default)
			)
			(layer "B.Fab")
		)
		(pad "1" smd circle
			(at 0.40005 0 270)
			(size 0 0)
			(layers "B.Cu" "B.Mask" "B.Paste")
			(net "P3V3_AUX")
		)
		(pad "2" smd circle
			(at -0.40005 0 270)
			(size 0 0)
			(layers "B.Cu" "B.Mask" "B.Paste")
			(net "GND")
		)
	)
	(footprint ""
		(layer "B.Cu")
		(at 37.792914 -244.085364 180)
		(property "Reference" "R503"
			(at 0 0 0)
			(layer "B.SilkS")
			(hide yes)
			(effects
				(font
					(size 1.27 1.27)
				)
				(justify mirror)
			)
		)
		(property "Value" ""
			(at 0 0 0)
			(layer "B.Fab")
			(effects
				(font
					(size 1.27 1.27)
				)
				(justify mirror)
			)
		)
		(duplicate_pad_numbers_are_jumpers no)
		(fp_line
			(start 0.7874 0.4064)
			(end 0.7874 -0.4064)
			(stroke
				(width 0.1524)
				(type default)
			)
			(layer "B.SilkS")
		)
		(fp_line
			(start 0.7874 -0.4064)
			(end -0.7874 -0.4064)
			(stroke
				(width 0.1524)
				(type default)
			)
			(layer "B.SilkS")
		)
		(fp_line
			(start -0.7874 0.4064)
			(end 0.7874 0.4064)
			(stroke
				(width 0.1524)
				(type default)
			)
			(layer "B.SilkS")
		)
		(fp_line
			(start -0.7874 -0.4064)
			(end -0.7874 0.4064)
			(stroke
				(width 0.1524)
				(type default)
			)
			(layer "B.SilkS")
		)
		(fp_line
			(start 0.67945 0.3048)
			(end 0.67945 -0.305054)
			(stroke
				(width 0.1)
				(type default)
			)
			(layer "B.Fab")
		)
		(fp_line
			(start 0.67945 -0.305054)
			(end 0.12065 -0.305054)
			(stroke
				(width 0.1)
				(type default)
			)
			(layer "B.Fab")
		)
		(fp_line
			(start 0.12065 0.3048)
			(end 0.67945 0.3048)
			(stroke
				(width 0.1)
				(type default)
			)
			(layer "B.Fab")
		)
		(fp_line
			(start 0.12065 0.2794)
			(end 0.12065 0.3048)
			(stroke
				(width 0.1)
				(type default)
			)
			(layer "B.Fab")
		)
		(fp_line
			(start 0.12065 -0.2794)
			(end -0.12065 -0.2794)
			(stroke
				(width 0.1)
				(type default)
			)
			(layer "B.Fab")
		)
		(fp_line
			(start 0.12065 -0.305054)
			(end 0.12065 -0.2794)
			(stroke
				(width 0.1)
				(type default)
			)
			(layer "B.Fab")
		)
		(fp_line
			(start -0.120396 0.3048)
			(end -0.120396 0.2794)
			(stroke
				(width 0.1)
				(type default)
			)
			(layer "B.Fab")
		)
		(fp_line
			(start -0.120396 0.2794)
			(end 0.12065 0.2794)
			(stroke
				(width 0.1)
				(type default)
			)
			(layer "B.Fab")
		)
		(fp_line
			(start -0.12065 -0.2794)
			(end -0.12065 -0.3048)
			(stroke
				(width 0.1)
				(type default)
			)
			(layer "B.Fab")
		)
		(fp_line
			(start -0.12065 -0.3048)
			(end -0.67945 -0.3048)
			(stroke
				(width 0.1)
				(type default)
			)
			(layer "B.Fab")
		)
		(fp_line
			(start -0.67945 0.3048)
			(end -0.120396 0.3048)
			(stroke
				(width 0.1)
				(type default)
			)
			(layer "B.Fab")
		)
		(fp_line
			(start -0.67945 -0.3048)
			(end -0.67945 0.3048)
			(stroke
				(width 0.1)
				(type default)
			)
			(layer "B.Fab")
		)
		(pad "1" smd circle
			(at 0.40005 0)
			(size 0 0)
			(layers "B.Cu" "B.Mask" "B.Paste")
			(net "M_D_CPU1_ALERT_N")
		)
		(pad "2" smd circle
			(at -0.40005 0)
			(size 0 0)
			(layers "B.Cu" "B.Mask" "B.Paste")
			(net "M_D_CPU1_ALERT_R_N")
		)
	)
	(footprint ""
		(layer "B.Cu")
		(at 93.10624 -386.766562 90)
		(property "Reference" "C315"
			(at 0 0 90)
			(layer "B.SilkS")
			(hide yes)
			(effects
				(font
					(size 1.27 1.27)
				)
				(justify mirror)
			)
		)
		(property "Value" ""
			(at 0 0 90)
			(layer "B.Fab")
			(effects
				(font
					(size 1.27 1.27)
				)
				(justify mirror)
			)
		)
		(duplicate_pad_numbers_are_jumpers no)
		(fp_line
			(start 0.299974 -0.150114)
			(end -0.299974 -0.150114)
			(stroke
				(width 0.1)
				(type default)
			)
			(layer "B.Fab")
		)
		(fp_line
			(start -0.299974 -0.150114)
			(end -0.299974 0.150114)
			(stroke
				(width 0.1)
				(type default)
			)
			(layer "B.Fab")
		)
		(fp_line
			(start 0.299974 0.150114)
			(end 0.299974 -0.150114)
			(stroke
				(width 0.1)
				(type default)
			)
			(layer "B.Fab")
		)
		(fp_line
			(start -0.299974 0.150114)
			(end 0.299974 0.150114)
			(stroke
				(width 0.1)
				(type default)
			)
			(layer "B.Fab")
		)
		(pad "1" smd rect
			(at 0.2667 0 270)
			(size 0.3048 0.381)
			(layers "B.Cu" "B.Mask" "B.Paste")
			(net "P0V9_CPU1_RT1_2A_2D")
		)
		(pad "2" smd rect
			(at -0.2667 0 270)
			(size 0.3048 0.381)
			(layers "B.Cu" "B.Mask" "B.Paste")
			(net "GND")
		)
	)
)
